# S9S_MB_2U (Grand Teton) — schematic netlist excerpt (pin names and nets, part order shuffled) for the footprints in the layout excerpt that follows; sources: Cadence DE-HDL packaged netlist, KiCad conversion of 03242023_DA0F0TMBIJ0_F0T_Motherboard_J_brd_V01_OCP.brd

PC630  Q_CAP  10UF 6.3V 20% X6S  pkg C0402  page 278 : A = PVCCD_HV_CPU0_VREF ; B = GND
R935  Q_RES  10K 1% CHIP  pkg 0402LF  page 128 : A = RST_CPU1_DRAM_CD_N ; B = GND

(kicad_pcb
	(version 20260206)
	(generator "pcbnew")
	(generator_version "10.0")
	(general
		(thickness 1.6)
		(legacy_teardrops no)
	)
	(paper "A4")
	(title_block
		(title "03242023_DA0F0TMBIJ0_F0T_Motherboard_J_brd_V01_OCP.brd")
		(comment 1 "Grand Teton / footprints 3086-3087 of 6105")
	)
	(layers
		(0 "F.Cu" signal "TOP")
		(4 "In1.Cu" signal "GND")
		(6 "In2.Cu" signal "IN1")
		(8 "In3.Cu" signal "GND1")
		(10 "In4.Cu" signal "IN2")
		(12 "In5.Cu" signal "GND2")
		(14 "In6.Cu" signal "IN3")
		(16 "In7.Cu" signal "GND3")
		(18 "In8.Cu" signal "VCC")
		(20 "In9.Cu" signal "VCC1")
		(22 "In10.Cu" signal "GND4")
		(24 "In11.Cu" signal "IN4")
		(26 "In12.Cu" signal "GND5")
		(28 "In13.Cu" signal "IN5")
		(30 "In14.Cu" signal "GND6")
		(32 "In15.Cu" signal "IN6")
		(34 "In16.Cu" signal "GND7")
		(2 "B.Cu" signal "BOTTOM")
		(9 "F.Adhes" user "F.Adhesive")
		(11 "B.Adhes" user "B.Adhesive")
		(13 "F.Paste" user "Package Geometry/Pastemask Top")
		(15 "B.Paste" user "Package Geometry/Pastemask Bottom")
		(5 "F.SilkS" user "Ref Des/Silkscreen Top")
		(7 "B.SilkS" user "Ref Des/Silkscreen Bottom")
		(1 "F.Mask" user "Board Geometry/Soldermask Top")
		(3 "B.Mask" user "Board Geometry/Soldermask Bottom")
		(17 "Dwgs.User" user "User.Drawings")
		(19 "Cmts.User" user "User.Comments")
		(21 "Eco1.User" user "User.Eco1")
		(23 "Eco2.User" user "User.Eco2")
		(25 "Edge.Cuts" user "Board Geometry/Outline")
		(27 "Margin" user)
		(31 "F.CrtYd" user "Package Geometry/Place Bound Top")
		(29 "B.CrtYd" user "Package Geometry/Place Bound Bottom")
		(35 "F.Fab" user "Ref Des/Assembly Top")
		(33 "B.Fab" user "Ref Des/Assembly Bottom")
	)
	(footprint ""
		(layer "F.Cu")
		(at 430.186592 -118.815104 -90)
		(property "Reference" "PC630"
			(at 0 0 270)
			(layer "F.SilkS")
			(hide yes)
			(effects
				(font
					(size 1.27 1.27)
				)
			)
		)
		(property "Value" ""
			(at 0 0 270)
			(layer "F.Fab")
			(effects
				(font
					(size 1.27 1.27)
				)
			)
		)
		(duplicate_pad_numbers_are_jumpers no)
		(fp_line
			(start -0.7874 0.4064)
			(end -0.7874 -0.4064)
			(stroke
				(width 0.1524)
				(type default)
			)
			(layer "F.SilkS")
		)
		(fp_line
			(start 0.7874 0.4064)
			(end -0.7874 0.4064)
			(stroke
				(width 0.1524)
				(type default)
			)
			(layer "F.SilkS")
		)
		(fp_line
			(start -0.7874 -0.4064)
			(end 0.7874 -0.4064)
			(stroke
				(width 0.1524)
				(type default)
			)
			(layer "F.SilkS")
		)
		(fp_line
			(start 0.7874 -0.4064)
			(end 0.7874 0.4064)
			(stroke
				(width 0.1524)
				(type default)
			)
			(layer "F.SilkS")
		)
		(fp_line
			(start -0.67945 0.3048)
			(end -0.67945 -0.305054)
			(stroke
				(width 0.1)
				(type default)
			)
			(layer "F.Fab")
		)
		(fp_line
			(start -0.12065 0.3048)
			(end -0.67945 0.3048)
			(stroke
				(width 0.1)
				(type default)
			)
			(layer "F.Fab")
		)
		(fp_line
			(start 0.120396 0.3048)
			(end 0.120396 0.2794)
			(stroke
				(width 0.1)
				(type default)
			)
			(layer "F.Fab")
		)
		(fp_line
			(start 0.67945 0.3048)
			(end 0.120396 0.3048)
			(stroke
				(width 0.1)
				(type default)
			)
			(layer "F.Fab")
		)
		(fp_line
			(start -0.12065 0.2794)
			(end -0.12065 0.3048)
			(stroke
				(width 0.1)
				(type default)
			)
			(layer "F.Fab")
		)
		(fp_line
			(start 0.120396 0.2794)
			(end -0.12065 0.2794)
			(stroke
				(width 0.1)
				(type default)
			)
			(layer "F.Fab")
		)
		(fp_line
			(start -0.12065 -0.2794)
			(end 0.12065 -0.2794)
			(stroke
				(width 0.1)
				(type default)
			)
			(layer "F.Fab")
		)
		(fp_line
			(start 0.12065 -0.2794)
			(end 0.12065 -0.3048)
			(stroke
				(width 0.1)
				(type default)
			)
			(layer "F.Fab")
		)
		(fp_line
			(start 0.12065 -0.3048)
			(end 0.67945 -0.3048)
			(stroke
				(width 0.1)
				(type default)
			)
			(layer "F.Fab")
		)
		(fp_line
			(start 0.67945 -0.3048)
			(end 0.67945 0.3048)
			(stroke
				(width 0.1)
				(type default)
			)
			(layer "F.Fab")
		)
		(fp_line
			(start -0.67945 -0.305054)
			(end -0.12065 -0.305054)
			(stroke
				(width 0.1)
				(type default)
			)
			(layer "F.Fab")
		)
		(fp_line
			(start -0.12065 -0.305054)
			(end -0.12065 -0.2794)
			(stroke
				(width 0.1)
				(type default)
			)
			(layer "F.Fab")
		)
		(pad "1" smd circle
			(at -0.40005 0 270)
			(size 0 0)
			(layers "F.Cu" "F.Mask" "F.Paste")
			(net "PVCCD_HV_CPU0_VREF")
		)
		(pad "2" smd circle
			(at 0.40005 0 270)
			(size 0 0)
			(layers "F.Cu" "F.Mask" "F.Paste")
			(net "GND")
		)
	)
	(footprint ""
		(layer "F.Cu")
		(at 121.708926 -122.096784 90)
		(property "Reference" "R935"
			(at 0 0 90)
			(layer "F.SilkS")
			(hide yes)
			(effects
				(font
					(size 1.27 1.27)
				)
			)
		)
		(property "Value" ""
			(at 0 0 90)
			(layer "F.Fab")
			(effects
				(font
					(size 1.27 1.27)
				)
			)
		)
		(duplicate_pad_numbers_are_jumpers no)
		(fp_line
			(start 0.7874 -0.4064)
			(end 0.7874 0.4064)
			(stroke
				(width 0.1524)
				(type default)
			)
			(layer "F.SilkS")
		)
		(fp_line
			(start -0.7874 -0.4064)
			(end 0.7874 -0.4064)
			(stroke
				(width 0.1524)
				(type default)
			)
			(layer "F.SilkS")
		)
		(fp_line
			(start 0.7874 0.4064)
			(end -0.7874 0.4064)
			(stroke
				(width 0.1524)
				(type default)
			)
			(layer "F.SilkS")
		)
		(fp_line
			(start -0.7874 0.4064)
			(end -0.7874 -0.4064)
			(stroke
				(width 0.1524)
				(type default)
			)
			(layer "F.SilkS")
		)
		(fp_line
			(start -0.12065 -0.305054)
			(end -0.12065 -0.2794)
			(stroke
				(width 0.1)
				(type default)
			)
			(layer "F.Fab")
		)
		(fp_line
			(start -0.67945 -0.305054)
			(end -0.12065 -0.305054)
			(stroke
				(width 0.1)
				(type default)
			)
			(layer "F.Fab")
		)
		(fp_line
			(start 0.67945 -0.3048)
			(end 0.67945 0.3048)
			(stroke
				(width 0.1)
				(type default)
			)
			(layer "F.Fab")
		)
		(fp_line
			(start 0.12065 -0.3048)
			(end 0.67945 -0.3048)
			(stroke
				(width 0.1)
				(type default)
			)
			(layer "F.Fab")
		)
		(fp_line
			(start 0.12065 -0.2794)
			(end 0.12065 -0.3048)
			(stroke
				(width 0.1)
				(type default)
			)
			(layer "F.Fab")
		)
		(fp_line
			(start -0.12065 -0.2794)
			(end 0.12065 -0.2794)
			(stroke
				(width 0.1)
				(type default)
			)
			(layer "F.Fab")
		)
		(fp_line
			(start 0.120396 0.2794)
			(end -0.12065 0.2794)
			(stroke
				(width 0.1)
				(type default)
			)
			(layer "F.Fab")
		)
		(fp_line
			(start -0.12065 0.2794)
			(end -0.12065 0.3048)
			(stroke
				(width 0.1)
				(type default)
			)
			(layer "F.Fab")
		)
		(fp_line
			(start 0.67945 0.3048)
			(end 0.120396 0.3048)
			(stroke
				(width 0.1)
				(type default)
			)
			(layer "F.Fab")
		)
		(fp_line
			(start 0.120396 0.3048)
			(end 0.120396 0.2794)
			(stroke
				(width 0.1)
				(type default)
			)
			(layer "F.Fab")
		)
		(fp_line
			(start -0.12065 0.3048)
			(end -0.67945 0.3048)
			(stroke
				(width 0.1)
				(type default)
			)
			(layer "F.Fab")
		)
		(fp_line
			(start -0.67945 0.3048)
			(end -0.67945 -0.305054)
			(stroke
				(width 0.1)
				(type default)
			)
			(layer "F.Fab")
		)
		(pad "1" smd circle
			(at -0.40005 0 90)
			(size 0 0)
			(layers "F.Cu" "F.Mask" "F.Paste")
			(net "RST_CPU1_DRAM_CD_N")
		)
		(pad "2" smd circle
			(at 0.40005 0 90)
			(size 0 0)
			(layers "F.Cu" "F.Mask" "F.Paste")
			(net "GND")
		)
	)
)
